# BASEBOARD_FAB2 (Tioga Pass) — schematic netlist excerpt (pin names and nets, part order shuffled) for the footprints in the layout excerpt that follows; sources: Cadence DE-HDL packaged netlist, KiCad conversion of Wiwynn_Tioga_Pass_MB.brd

J4B2  SCONN120_H61426002  CONN  pkg SM  page 193
  IOA1  = P12V_STBY
  IOA2  = P12V_STBY
  IOA3  = P12V_STBY
  IOA4  = P12V_STBY
  IOA5  = P12V_STBY
  IOA6  = P12V_STBY
  IOA7  = P12V_STBY
  IOA8  = P12V_STBY
  IOA9  = GND
  IOA10  = GND
  IOA11  = P3V3_STBY
  IOA12  = GND
  IOA13  = P5V_STBY
  IOA14  = GND
  IOA15  = FM_P1V8MCP_CPU1_EN
  IOA16  = FM_PVCCIOMCP_CPU1_EN
  IOA17  = GND
  IOA18  = SMB_VR_STBY_LVC3_SCL
  IOA19  = SVID_ALERT0_CPU1_R_N
  IOA20  = SVID_CLK0_CPU1_R
  IOB1  = P12V_STBY
  IOB2  = P12V_STBY
  IOB3  = P12V_STBY
  IOB4  = P12V_STBY
  IOB5  = P12V_STBY
  IOB6  = P12V_STBY
  IOB7  = P12V_STBY
  IOB8  = P12V_STBY
  IOB9  = GND
  IOB10  = GND
  IOB11  = P3V3_STBY
  IOB12  = GND
  IOB13  = P5V_STBY
  IOB14  = GND
  IOB15  = PWRGD_P1V8MCP_CPU1
  IOB16  = PWRGD_PVCCIOMCP_CPU1
  IOB17  = GND
  IOB18  = SMB_VR_STBY_LVC3_SDA
  IOB19  = SVID_ALERT1_CPU1_R_N
  IOB20  = SVID_DIO0_CPU1_R
  IOC1  = GND
  IOC2  = GND
  IOC3  = GND
  IOC4  = GND
  IOC5  = GND
  IOC6  = GND
  IOC7  = GND
  IOC8  = GND
  IOC9  = GND
  IOC10  = GND
  IOC11  = P3V3_STBY
  IOC12  = GND
  IOC13  = P5V_STBY
  IOC14  = GND
  IOC15  = GND
  IOC16  = GND
  IOC17  = PVCCIOMCP_CPU1
  IOC18  = PVCCIOMCP_CPU1
  IOC19  = PVCCIOMCP_CPU1
  IOC20  = FM_PVCCMCP_CPU1_EN
  IOD1  = P3V3
  IOD2  = GND
  IOD3  = GND
  IOD4  = GND
  IOD5  = GND
  IOD6  = GND
  IOD7  = GND
  IOD8  = GND
  IOD9  = GND
  IOD10  = GND
  IOD11  = GND
  IOD12  = GND
  IOD13  = GND
  IOD14  = GND
  IOD15  = GND
  IOD16  = GND
  IOD17  = PVCCIOMCP_CPU1
  IOD18  = PVCCIOMCP_CPU1
  IOD19  = PVCCIOMCP_CPU1
  IOD20  = PWRGD_PVCCMCP_CPU1
  IOE1  = FM_CPU1_VRM_322M_156M_OSC_EN
  IOE2  = GND
  IOE3  = GND
  IOE4  = GND
  IOE5  = GND
  IOE6  = GND
  IOE7  = GND
  IOE8  = VSENSE_PVCCIOMCP_CPU1_SKT_VSEN
  IOE9  = GND
  IOE10  = VR_PVCCIOMCP_CPU1_XADDR1
  IOE11  = GND
  IOE12  = GND
  IOE13  = GND
  IOE14  = GND
  IOE15  = PVCCIOMCP_CPU1
  IOE16  = PVCCIOMCP_CPU1
  IOE17  = PVCCIOMCP_CPU1
  IOE18  = PVCCIOMCP_CPU1
  IOE19  = PVCCIOMCP_CPU1
  IOE20  = SVID_CLK1_CPU1_R
  IOF1  = PVCCIO_CPU1
  IOF2  = GND
  IOF3  = GND
  IOF4  = GND
  IOF5  = GND
  IOF6  = GND
  IOF7  = GND
  IOF8  = VSENSE_PVCCIOMCP_CPU1_SKT_VRTN
  IOF9  = GND
  IOF10  = VR_PVCCMCP_CPU1_XADDR2
  IOF11  = GND
  IOF12  = GND
  IOF13  = GND
  IOF14  = GND
  IOF15  = PVCCIOMCP_CPU1
  IOF16  = PVCCIOMCP_CPU1
  IOF17  = PVCCIOMCP_CPU1
  IOF18  = PVCCIOMCP_CPU1
  IOF19  = PVCCIOMCP_CPU1
  IOF20  = SVID_DIO1_CPU1_R

(kicad_pcb
	(version 20260206)
	(generator "pcbnew")
	(generator_version "10.0")
	(general
		(thickness 1.6)
		(legacy_teardrops no)
	)
	(paper "A4")
	(title_block
		(title "Wiwynn_Tioga_Pass_MB.brd")
		(comment 1 "Tioga Pass / footprint 858 of 4770 (J4B2), pads 52-102 of 122")
	)
	(layers
		(0 "F.Cu" signal "TOP")
		(4 "In1.Cu" signal "L2GND")
		(6 "In2.Cu" signal "L3")
		(8 "In3.Cu" signal "L4GND")
		(10 "In4.Cu" signal "L5")
		(12 "In5.Cu" signal "L6GND")
		(14 "In6.Cu" signal "L7VCC")
		(16 "In7.Cu" signal "L8VCC")
		(18 "In8.Cu" signal "L9GND")
		(20 "In9.Cu" signal "L10")
		(22 "In10.Cu" signal "L11GND")
		(24 "In11.Cu" signal "L12")
		(26 "In12.Cu" signal "L13GND")
		(2 "B.Cu" signal "BOTTOM")
		(9 "F.Adhes" user "F.Adhesive")
		(11 "B.Adhes" user "B.Adhesive")
		(13 "F.Paste" user "Package Geometry/Pastemask Top")
		(15 "B.Paste" user "Package Geometry/Pastemask Bottom")
		(5 "F.SilkS" user "Ref Des/Silkscreen Top")
		(7 "B.SilkS" user "Ref Des/Silkscreen Bottom")
		(1 "F.Mask" user "Board Geometry/Soldermask Top")
		(3 "B.Mask" user "Board Geometry/Soldermask Bottom")
		(17 "Dwgs.User" user "User.Drawings")
		(19 "Cmts.User" user "User.Comments")
		(21 "Eco1.User" user "User.Eco1")
		(23 "Eco2.User" user "User.Eco2")
		(25 "Edge.Cuts" user "Board Geometry/Outline")
		(27 "Margin" user)
		(31 "F.CrtYd" user "Package Geometry/Place Bound Top")
		(29 "B.CrtYd" user "Package Geometry/Place Bound Bottom")
		(35 "F.Fab" user "Ref Des/Assembly Top")
		(33 "B.Fab" user "Ref Des/Assembly Bottom")
	)
	(footprint ""
		(layer "F.Cu")
		(at 164.615114 -115.55095 90)
		(property "Reference" "J4B2"
			(at -3.59283 -5.018024 90)
			(unlocked yes)
			(layer "F.SilkS")
			(effects
				(font
					(size 0.7874 0.5842)
					(thickness 0.1524)
				)
			)
		)
		(property "Value" ""
			(at 0 0 90)
			(layer "F.Fab")
			(effects
				(font
					(size 1.27 1.27)
				)
			)
		)
		(duplicate_pad_numbers_are_jumpers no)
		(pad "C10" smd circle
			(at -2.54 11.43 90)
			(size 0.635 0.635)
			(layers "F.Cu" "F.Mask" "F.Paste")
			(net "GND")
		)
		(pad "C11" smd circle
			(at -2.54 12.7 90)
			(size 0.635 0.635)
			(layers "F.Cu" "F.Mask" "F.Paste")
			(net "P3V3_STBY")
		)
		(pad "C12" smd circle
			(at -2.54 13.97 90)
			(size 0.635 0.635)
			(layers "F.Cu" "F.Mask" "F.Paste")
			(net "GND")
		)
		(pad "C13" smd circle
			(at -2.54 15.24 90)
			(size 0.635 0.635)
			(layers "F.Cu" "F.Mask" "F.Paste")
			(net "P5V_STBY")
		)
		(pad "C14" smd circle
			(at -2.54 16.51 90)
			(size 0.635 0.635)
			(layers "F.Cu" "F.Mask" "F.Paste")
			(net "GND")
		)
		(pad "C15" smd circle
			(at -2.54 17.78 90)
			(size 0.635 0.635)
			(layers "F.Cu" "F.Mask" "F.Paste")
			(net "GND")
		)
		(pad "C16" smd circle
			(at -2.54 19.05 90)
			(size 0.635 0.635)
			(layers "F.Cu" "F.Mask" "F.Paste")
			(net "GND")
		)
		(pad "C17" smd circle
			(at -2.54 20.32 90)
			(size 0.635 0.635)
			(layers "F.Cu" "F.Mask" "F.Paste")
			(net "PVCCIOMCP_CPU1")
		)
		(pad "C18" smd circle
			(at -2.54 21.59 90)
			(size 0.635 0.635)
			(layers "F.Cu" "F.Mask" "F.Paste")
			(net "PVCCIOMCP_CPU1")
		)
		(pad "C19" smd circle
			(at -2.54 22.86 90)
			(size 0.635 0.635)
			(layers "F.Cu" "F.Mask" "F.Paste")
			(net "PVCCIOMCP_CPU1")
		)
		(pad "C20" smd circle
			(at -2.54 24.13 90)
			(size 0.635 0.635)
			(layers "F.Cu" "F.Mask" "F.Paste")
			(net "FM_PVCCMCP_CPU1_EN")
		)
		(pad "D1" smd circle
			(at -3.81 0 90)
			(size 0.635 0.635)
			(layers "F.Cu" "F.Mask" "F.Paste")
			(net "P3V3")
		)
		(pad "D2" smd circle
			(at -3.81 1.27 90)
			(size 0.635 0.635)
			(layers "F.Cu" "F.Mask" "F.Paste")
			(net "GND")
		)
		(pad "D3" smd circle
			(at -3.81 2.54 90)
			(size 0.635 0.635)
			(layers "F.Cu" "F.Mask" "F.Paste")
			(net "GND")
		)
		(pad "D4" smd circle
			(at -3.81 3.81 90)
			(size 0.635 0.635)
			(layers "F.Cu" "F.Mask" "F.Paste")
			(net "GND")
		)
		(pad "D5" smd circle
			(at -3.81 5.08 90)
			(size 0.635 0.635)
			(layers "F.Cu" "F.Mask" "F.Paste")
			(net "GND")
		)
		(pad "D6" smd circle
			(at -3.81 6.35 90)
			(size 0.635 0.635)
			(layers "F.Cu" "F.Mask" "F.Paste")
			(net "GND")
		)
		(pad "D7" smd circle
			(at -3.81 7.62 90)
			(size 0.635 0.635)
			(layers "F.Cu" "F.Mask" "F.Paste")
			(net "GND")
		)
		(pad "D8" smd circle
			(at -3.81 8.89 90)
			(size 0.635 0.635)
			(layers "F.Cu" "F.Mask" "F.Paste")
			(net "GND")
		)
		(pad "D9" smd circle
			(at -3.81 10.16 90)
			(size 0.635 0.635)
			(layers "F.Cu" "F.Mask" "F.Paste")
			(net "GND")
		)
		(pad "D10" smd circle
			(at -3.81 11.43 90)
			(size 0.635 0.635)
			(layers "F.Cu" "F.Mask" "F.Paste")
			(net "GND")
		)
		(pad "D11" smd circle
			(at -3.81 12.7 90)
			(size 0.635 0.635)
			(layers "F.Cu" "F.Mask" "F.Paste")
			(net "GND")
		)
		(pad "D12" smd circle
			(at -3.81 13.97 90)
			(size 0.635 0.635)
			(layers "F.Cu" "F.Mask" "F.Paste")
			(net "GND")
		)
		(pad "D13" smd circle
			(at -3.81 15.24 90)
			(size 0.635 0.635)
			(layers "F.Cu" "F.Mask" "F.Paste")
			(net "GND")
		)
		(pad "D14" smd circle
			(at -3.81 16.51 90)
			(size 0.635 0.635)
			(layers "F.Cu" "F.Mask" "F.Paste")
			(net "GND")
		)
		(pad "D15" smd circle
			(at -3.81 17.78 90)
			(size 0.635 0.635)
			(layers "F.Cu" "F.Mask" "F.Paste")
			(net "GND")
		)
		(pad "D16" smd circle
			(at -3.81 19.05 90)
			(size 0.635 0.635)
			(layers "F.Cu" "F.Mask" "F.Paste")
			(net "GND")
		)
		(pad "D17" smd circle
			(at -3.81 20.32 90)
			(size 0.635 0.635)
			(layers "F.Cu" "F.Mask" "F.Paste")
			(net "PVCCIOMCP_CPU1")
		)
		(pad "D18" smd circle
			(at -3.81 21.59 90)
			(size 0.635 0.635)
			(layers "F.Cu" "F.Mask" "F.Paste")
			(net "PVCCIOMCP_CPU1")
		)
		(pad "D19" smd circle
			(at -3.81 22.86 90)
			(size 0.635 0.635)
			(layers "F.Cu" "F.Mask" "F.Paste")
			(net "PVCCIOMCP_CPU1")
		)
		(pad "D20" smd circle
			(at -3.81 24.13 90)
			(size 0.635 0.635)
			(layers "F.Cu" "F.Mask" "F.Paste")
			(net "PWRGD_PVCCMCP_CPU1")
		)
		(pad "E1" smd circle
			(at -5.08 0 90)
			(size 0.635 0.635)
			(layers "F.Cu" "F.Mask" "F.Paste")
			(net "FM_CPU1_VRM_322M_156M_OSC_EN")
		)
		(pad "E2" smd circle
			(at -5.08 1.27 90)
			(size 0.635 0.635)
			(layers "F.Cu" "F.Mask" "F.Paste")
			(net "GND")
		)
		(pad "E3" smd circle
			(at -5.08 2.54 90)
			(size 0.635 0.635)
			(layers "F.Cu" "F.Mask" "F.Paste")
			(net "GND")
		)
		(pad "E4" smd circle
			(at -5.08 3.81 90)
			(size 0.635 0.635)
			(layers "F.Cu" "F.Mask" "F.Paste")
			(net "GND")
		)
		(pad "E5" smd circle
			(at -5.08 5.08 90)
			(size 0.635 0.635)
			(layers "F.Cu" "F.Mask" "F.Paste")
			(net "GND")
		)
		(pad "E6" smd circle
			(at -5.08 6.35 90)
			(size 0.635 0.635)
			(layers "F.Cu" "F.Mask" "F.Paste")
			(net "GND")
		)
		(pad "E7" smd circle
			(at -5.08 7.62 90)
			(size 0.635 0.635)
			(layers "F.Cu" "F.Mask" "F.Paste")
			(net "GND")
		)
		(pad "E8" smd circle
			(at -5.08 8.89 90)
			(size 0.635 0.635)
			(layers "F.Cu" "F.Mask" "F.Paste")
			(net "VSENSE_PVCCIOMCP_CPU1_SKT_VSEN")
		)
		(pad "E9" smd circle
			(at -5.08 10.16 90)
			(size 0.635 0.635)
			(layers "F.Cu" "F.Mask" "F.Paste")
			(net "GND")
		)
		(pad "E10" smd circle
			(at -5.08 11.43 90)
			(size 0.635 0.635)
			(layers "F.Cu" "F.Mask" "F.Paste")
			(net "VR_PVCCIOMCP_CPU1_XADDR1")
		)
		(pad "E11" smd circle
			(at -5.08 12.7 90)
			(size 0.635 0.635)
			(layers "F.Cu" "F.Mask" "F.Paste")
			(net "GND")
		)
		(pad "E12" smd circle
			(at -5.08 13.97 90)
			(size 0.635 0.635)
			(layers "F.Cu" "F.Mask" "F.Paste")
			(net "GND")
		)
		(pad "E13" smd circle
			(at -5.08 15.24 90)
			(size 0.635 0.635)
			(layers "F.Cu" "F.Mask" "F.Paste")
			(net "GND")
		)
		(pad "E14" smd circle
			(at -5.08 16.51 90)
			(size 0.635 0.635)
			(layers "F.Cu" "F.Mask" "F.Paste")
			(net "GND")
		)
		(pad "E15" smd circle
			(at -5.08 17.78 90)
			(size 0.635 0.635)
			(layers "F.Cu" "F.Mask" "F.Paste")
			(net "PVCCIOMCP_CPU1")
		)
		(pad "E16" smd circle
			(at -5.08 19.05 90)
			(size 0.635 0.635)
			(layers "F.Cu" "F.Mask" "F.Paste")
			(net "PVCCIOMCP_CPU1")
		)
		(pad "E17" smd circle
			(at -5.08 20.32 90)
			(size 0.635 0.635)
			(layers "F.Cu" "F.Mask" "F.Paste")
			(net "PVCCIOMCP_CPU1")
		)
		(pad "E18" smd circle
			(at -5.08 21.59 90)
			(size 0.635 0.635)
			(layers "F.Cu" "F.Mask" "F.Paste")
			(net "PVCCIOMCP_CPU1")
		)
		(pad "E19" smd circle
			(at -5.08 22.86 90)
			(size 0.635 0.635)
			(layers "F.Cu" "F.Mask" "F.Paste")
			(net "PVCCIOMCP_CPU1")
		)
		(pad "E20" smd circle
			(at -5.08 24.13 90)
			(size 0.635 0.635)
			(layers "F.Cu" "F.Mask" "F.Paste")
			(net "SVID_CLK1_CPU1_R")
		)
	)
)
